(kicad_pcb
	(version 20260206)
	(generator "pcbnew")
	(generator_version "10.0")
	(general
		(thickness 1.6)
		(legacy_teardrops no)
	)
	(paper "A4")
	(title_block
		(title "01162023_DA0F0TEBIF0_F0T_Expander_BD_F_brd_V02_OCP.brd")
		(comment 1 "Grand Teton / footprints 8717-8724 of 9728")
	)
	(layers
		(0 "F.Cu" signal "TOP")
		(4 "In1.Cu" signal "GND")
		(6 "In2.Cu" signal "VCC")
		(8 "In3.Cu" signal "VCC1")
		(10 "In4.Cu" signal "GND1")
		(12 "In5.Cu" signal "IN1")
		(14 "In6.Cu" signal "GND2")
		(16 "In7.Cu" signal "IN2")
		(18 "In8.Cu" signal "GND3")
		(20 "In9.Cu" signal "IN3")
		(22 "In10.Cu" signal "GND4")
		(24 "In11.Cu" signal "IN4")
		(26 "In12.Cu" signal "GND5")
		(28 "In13.Cu" signal "IN5")
		(30 "In14.Cu" signal "GND6")
		(32 "In15.Cu" signal "IN6")
		(34 "In16.Cu" signal "GND7")
		(2 "B.Cu" signal "BOTTOM")
		(9 "F.Adhes" user "F.Adhesive")
		(11 "B.Adhes" user "B.Adhesive")
		(13 "F.Paste" user "Package Geometry/Pastemask Top")
		(15 "B.Paste" user "Package Geometry/Pastemask Bottom")
		(5 "F.SilkS" user "Ref Des/Silkscreen Top")
		(7 "B.SilkS" user "Ref Des/Silkscreen Bottom")
		(1 "F.Mask" user "Board Geometry/Soldermask Top")
		(3 "B.Mask" user "Board Geometry/Soldermask Bottom")
		(17 "Dwgs.User" user "User.Drawings")
		(19 "Cmts.User" user "User.Comments")
		(21 "Eco1.User" user "User.Eco1")
		(23 "Eco2.User" user "User.Eco2")
		(25 "Edge.Cuts" user "Board Geometry/Outline")
		(27 "Margin" user)
		(31 "F.CrtYd" user "Package Geometry/Place Bound Top")
		(29 "B.CrtYd" user "Package Geometry/Place Bound Bottom")
		(35 "F.Fab" user "Ref Des/Assembly Top")
		(33 "B.Fab" user "Ref Des/Assembly Bottom")
	)
	(footprint ""
		(layer "B.Cu")
		(at 134.717536 -215.85682 180)
		(property "Reference" "R995"
			(at 0 0 0)
			(layer "B.SilkS")
			(hide yes)
			(effects
				(font
					(size 1.27 1.27)
				)
				(justify mirror)
			)
		)
		(property "Value" ""
			(at 0 0 0)
			(layer "B.Fab")
			(effects
				(font
					(size 1.27 1.27)
				)
				(justify mirror)
			)
		)
		(duplicate_pad_numbers_are_jumpers no)
		(fp_line
			(start 0.7874 0.4064)
			(end 0.7874 -0.4064)
			(stroke
				(width 0.1524)
				(type default)
			)
			(layer "B.SilkS")
		)
		(fp_line
			(start 0.7874 -0.4064)
			(end -0.7874 -0.4064)
			(stroke
				(width 0.1524)
				(type default)
			)
			(layer "B.SilkS")
		)
		(fp_line
			(start -0.7874 0.4064)
			(end 0.7874 0.4064)
			(stroke
				(width 0.1524)
				(type default)
			)
			(layer "B.SilkS")
		)
		(fp_line
			(start -0.7874 -0.4064)
			(end -0.7874 0.4064)
			(stroke
				(width 0.1524)
				(type default)
			)
			(layer "B.SilkS")
		)
		(fp_line
			(start 0.67945 0.3048)
			(end 0.67945 -0.305054)
			(stroke
				(width 0.1)
				(type default)
			)
			(layer "B.Fab")
		)
		(fp_line
			(start 0.67945 -0.305054)
			(end 0.12065 -0.305054)
			(stroke
				(width 0.1)
				(type default)
			)
			(layer "B.Fab")
		)
		(fp_line
			(start 0.12065 0.3048)
			(end 0.67945 0.3048)
			(stroke
				(width 0.1)
				(type default)
			)
			(layer "B.Fab")
		)
		(fp_line
			(start 0.12065 0.2794)
			(end 0.12065 0.3048)
			(stroke
				(width 0.1)
				(type default)
			)
			(layer "B.Fab")
		)
		(fp_line
			(start 0.12065 -0.2794)
			(end -0.12065 -0.2794)
			(stroke
				(width 0.1)
				(type default)
			)
			(layer "B.Fab")
		)
		(fp_line
			(start 0.12065 -0.305054)
			(end 0.12065 -0.2794)
			(stroke
				(width 0.1)
				(type default)
			)
			(layer "B.Fab")
		)
		(fp_line
			(start -0.120396 0.3048)
			(end -0.120396 0.2794)
			(stroke
				(width 0.1)
				(type default)
			)
			(layer "B.Fab")
		)
		(fp_line
			(start -0.120396 0.2794)
			(end 0.12065 0.2794)
			(stroke
				(width 0.1)
				(type default)
			)
			(layer "B.Fab")
		)
		(fp_line
			(start -0.12065 -0.2794)
			(end -0.12065 -0.3048)
			(stroke
				(width 0.1)
				(type default)
			)
			(layer "B.Fab")
		)
		(fp_line
			(start -0.12065 -0.3048)
			(end -0.67945 -0.3048)
			(stroke
				(width 0.1)
				(type default)
			)
			(layer "B.Fab")
		)
		(fp_line
			(start -0.67945 0.3048)
			(end -0.120396 0.3048)
			(stroke
				(width 0.1)
				(type default)
			)
			(layer "B.Fab")
		)
		(fp_line
			(start -0.67945 -0.3048)
			(end -0.67945 0.3048)
			(stroke
				(width 0.1)
				(type default)
			)
			(layer "B.Fab")
		)
		(pad "1" smd circle
			(at 0.40005 0)
			(size 0 0)
			(layers "B.Cu" "B.Mask" "B.Paste")
			(net "UART_PEX3_CLI_BUF_TX")
		)
		(pad "2" smd circle
			(at -0.40005 0)
			(size 0 0)
			(layers "B.Cu" "B.Mask" "B.Paste")
			(net "P3V3_AUX")
		)
	)
	(footprint ""
		(layer "B.Cu")
		(at 185.2676 -295.3512 180)
		(property "Reference" "C1418"
			(at 0 0 0)
			(layer "B.SilkS")
			(hide yes)
			(effects
				(font
					(size 1.27 1.27)
				)
				(justify mirror)
			)
		)
		(property "Value" ""
			(at 0 0 0)
			(layer "B.Fab")
			(effects
				(font
					(size 1.27 1.27)
				)
				(justify mirror)
			)
		)
		(duplicate_pad_numbers_are_jumpers no)
		(fp_line
			(start 0.299974 0.150114)
			(end 0.299974 -0.150114)
			(stroke
				(width 0.1)
				(type default)
			)
			(layer "B.Fab")
		)
		(fp_line
			(start 0.299974 -0.150114)
			(end -0.299974 -0.150114)
			(stroke
				(width 0.1)
				(type default)
			)
			(layer "B.Fab")
		)
		(fp_line
			(start -0.299974 0.150114)
			(end 0.299974 0.150114)
			(stroke
				(width 0.1)
				(type default)
			)
			(layer "B.Fab")
		)
		(fp_line
			(start -0.299974 -0.150114)
			(end -0.299974 0.150114)
			(stroke
				(width 0.1)
				(type default)
			)
			(layer "B.Fab")
		)
		(pad "1" smd rect
			(at 0.2667 0)
			(size 0.3048 0.381)
			(layers "B.Cu" "B.Mask" "B.Paste")
			(net "P0V8_SERDES_VDDA_PEX1")
		)
		(pad "2" smd rect
			(at -0.2667 0)
			(size 0.3048 0.381)
			(layers "B.Cu" "B.Mask" "B.Paste")
			(net "GND")
		)
	)
	(footprint ""
		(layer "B.Cu")
		(at 189.049914 -296.8498 180)
		(property "Reference" "C3122"
			(at 0 0 0)
			(layer "B.SilkS")
			(hide yes)
			(effects
				(font
					(size 1.27 1.27)
				)
				(justify mirror)
			)
		)
		(property "Value" ""
			(at 0 0 0)
			(layer "B.Fab")
			(effects
				(font
					(size 1.27 1.27)
				)
				(justify mirror)
			)
		)
		(duplicate_pad_numbers_are_jumpers no)
		(fp_line
			(start 0.299974 0.150114)
			(end 0.299974 -0.150114)
			(stroke
				(width 0.1)
				(type default)
			)
			(layer "B.Fab")
		)
		(fp_line
			(start 0.299974 -0.150114)
			(end -0.299974 -0.150114)
			(stroke
				(width 0.1)
				(type default)
			)
			(layer "B.Fab")
		)
		(fp_line
			(start -0.299974 0.150114)
			(end 0.299974 0.150114)
			(stroke
				(width 0.1)
				(type default)
			)
			(layer "B.Fab")
		)
		(fp_line
			(start -0.299974 -0.150114)
			(end -0.299974 0.150114)
			(stroke
				(width 0.1)
				(type default)
			)
			(layer "B.Fab")
		)
		(pad "1" smd rect
			(at 0.2667 0)
			(size 0.3048 0.381)
			(layers "B.Cu" "B.Mask" "B.Paste")
			(net "P1V25_SERDES_VDDPLL_PEX1")
		)
		(pad "2" smd rect
			(at -0.2667 0)
			(size 0.3048 0.381)
			(layers "B.Cu" "B.Mask" "B.Paste")
			(net "GND")
		)
	)
	(footprint ""
		(layer "B.Cu")
		(at 224.851976 -370.042186)
		(property "Reference" "PR35"
			(at 0 0 0)
			(layer "B.SilkS")
			(hide yes)
			(effects
				(font
					(size 1.27 1.27)
				)
				(justify mirror)
			)
		)
		(property "Value" ""
			(at 0 0 0)
			(layer "B.Fab")
			(effects
				(font
					(size 1.27 1.27)
				)
				(justify mirror)
			)
		)
		(duplicate_pad_numbers_are_jumpers no)
		(fp_line
			(start -0.7874 -0.4064)
			(end -0.7874 0.4064)
			(stroke
				(width 0.1524)
				(type default)
			)
			(layer "B.SilkS")
		)
		(fp_line
			(start -0.7874 0.4064)
			(end 0.7874 0.4064)
			(stroke
				(width 0.1524)
				(type default)
			)
			(layer "B.SilkS")
		)
		(fp_line
			(start 0.7874 -0.4064)
			(end -0.7874 -0.4064)
			(stroke
				(width 0.1524)
				(type default)
			)
			(layer "B.SilkS")
		)
		(fp_line
			(start 0.7874 0.4064)
			(end 0.7874 -0.4064)
			(stroke
				(width 0.1524)
				(type default)
			)
			(layer "B.SilkS")
		)
		(fp_line
			(start -0.67945 -0.3048)
			(end -0.67945 0.3048)
			(stroke
				(width 0.1)
				(type default)
			)
			(layer "B.Fab")
		)
		(fp_line
			(start -0.67945 0.3048)
			(end -0.120396 0.3048)
			(stroke
				(width 0.1)
				(type default)
			)
			(layer "B.Fab")
		)
		(fp_line
			(start -0.12065 -0.3048)
			(end -0.67945 -0.3048)
			(stroke
				(width 0.1)
				(type default)
			)
			(layer "B.Fab")
		)
		(fp_line
			(start -0.12065 -0.2794)
			(end -0.12065 -0.3048)
			(stroke
				(width 0.1)
				(type default)
			)
			(layer "B.Fab")
		)
		(fp_line
			(start -0.120396 0.2794)
			(end 0.12065 0.2794)
			(stroke
				(width 0.1)
				(type default)
			)
			(layer "B.Fab")
		)
		(fp_line
			(start -0.120396 0.3048)
			(end -0.120396 0.2794)
			(stroke
				(width 0.1)
				(type default)
			)
			(layer "B.Fab")
		)
		(fp_line
			(start 0.12065 -0.305054)
			(end 0.12065 -0.2794)
			(stroke
				(width 0.1)
				(type default)
			)
			(layer "B.Fab")
		)
		(fp_line
			(start 0.12065 -0.2794)
			(end -0.12065 -0.2794)
			(stroke
				(width 0.1)
				(type default)
			)
			(layer "B.Fab")
		)
		(fp_line
			(start 0.12065 0.2794)
			(end 0.12065 0.3048)
			(stroke
				(width 0.1)
				(type default)
			)
			(layer "B.Fab")
		)
		(fp_line
			(start 0.12065 0.3048)
			(end 0.67945 0.3048)
			(stroke
				(width 0.1)
				(type default)
			)
			(layer "B.Fab")
		)
		(fp_line
			(start 0.67945 -0.305054)
			(end 0.12065 -0.305054)
			(stroke
				(width 0.1)
				(type default)
			)
			(layer "B.Fab")
		)
		(fp_line
			(start 0.67945 0.3048)
			(end 0.67945 -0.305054)
			(stroke
				(width 0.1)
				(type default)
			)
			(layer "B.Fab")
		)
		(pad "1" smd circle
			(at 0.40005 0 180)
			(size 0 0)
			(layers "B.Cu" "B.Mask" "B.Paste")
			(net "HSC_VDD_2")
		)
		(pad "2" smd circle
			(at -0.40005 0 180)
			(size 0 0)
			(layers "B.Cu" "B.Mask" "B.Paste")
			(net "HSC_VDD")
		)
	)
	(footprint ""
		(layer "B.Cu")
		(at 231.901746 -149.000464)
		(property "Reference" "C2786"
			(at 0 0 0)
			(layer "B.SilkS")
			(hide yes)
			(effects
				(font
					(size 1.27 1.27)
				)
				(justify mirror)
			)
		)
		(property "Value" ""
			(at 0 0 0)
			(layer "B.Fab")
			(effects
				(font
					(size 1.27 1.27)
				)
				(justify mirror)
			)
		)
		(duplicate_pad_numbers_are_jumpers no)
		(fp_line
			(start -0.7874 -0.4064)
			(end -0.7874 0.4064)
			(stroke
				(width 0.1524)
				(type default)
			)
			(layer "B.SilkS")
		)
		(fp_line
			(start -0.7874 0.4064)
			(end 0.7874 0.4064)
			(stroke
				(width 0.1524)
				(type default)
			)
			(layer "B.SilkS")
		)
		(fp_line
			(start 0.7874 -0.4064)
			(end -0.7874 -0.4064)
			(stroke
				(width 0.1524)
				(type default)
			)
			(layer "B.SilkS")
		)
		(fp_line
			(start 0.7874 0.4064)
			(end 0.7874 -0.4064)
			(stroke
				(width 0.1524)
				(type default)
			)
			(layer "B.SilkS")
		)
		(fp_line
			(start -0.67945 -0.3048)
			(end -0.67945 0.3048)
			(stroke
				(width 0.1)
				(type default)
			)
			(layer "B.Fab")
		)
		(fp_line
			(start -0.67945 0.3048)
			(end -0.120396 0.3048)
			(stroke
				(width 0.1)
				(type default)
			)
			(layer "B.Fab")
		)
		(fp_line
			(start -0.12065 -0.3048)
			(end -0.67945 -0.3048)
			(stroke
				(width 0.1)
				(type default)
			)
			(layer "B.Fab")
		)
		(fp_line
			(start -0.12065 -0.2794)
			(end -0.12065 -0.3048)
			(stroke
				(width 0.1)
				(type default)
			)
			(layer "B.Fab")
		)
		(fp_line
			(start -0.120396 0.2794)
			(end 0.12065 0.2794)
			(stroke
				(width 0.1)
				(type default)
			)
			(layer "B.Fab")
		)
		(fp_line
			(start -0.120396 0.3048)
			(end -0.120396 0.2794)
			(stroke
				(width 0.1)
				(type default)
			)
			(layer "B.Fab")
		)
		(fp_line
			(start 0.12065 -0.305054)
			(end 0.12065 -0.2794)
			(stroke
				(width 0.1)
				(type default)
			)
			(layer "B.Fab")
		)
		(fp_line
			(start 0.12065 -0.2794)
			(end -0.12065 -0.2794)
			(stroke
				(width 0.1)
				(type default)
			)
			(layer "B.Fab")
		)
		(fp_line
			(start 0.12065 0.2794)
			(end 0.12065 0.3048)
			(stroke
				(width 0.1)
				(type default)
			)
			(layer "B.Fab")
		)
		(fp_line
			(start 0.12065 0.3048)
			(end 0.67945 0.3048)
			(stroke
				(width 0.1)
				(type default)
			)
			(layer "B.Fab")
		)
		(fp_line
			(start 0.67945 -0.305054)
			(end 0.12065 -0.305054)
			(stroke
				(width 0.1)
				(type default)
			)
			(layer "B.Fab")
		)
		(fp_line
			(start 0.67945 0.3048)
			(end 0.67945 -0.305054)
			(stroke
				(width 0.1)
				(type default)
			)
			(layer "B.Fab")
		)
		(pad "1" smd circle
			(at 0.40005 0 180)
			(size 0 0)
			(layers "B.Cu" "B.Mask" "B.Paste")
			(net "P3V3_CLK_GEN_VDD_CK440_PEX")
		)
		(pad "2" smd circle
			(at -0.40005 0 180)
			(size 0 0)
			(layers "B.Cu" "B.Mask" "B.Paste")
			(net "GND")
		)
	)
	(footprint ""
		(layer "B.Cu")
		(at 49.5554 -155.0416)
		(property "Reference" "R27"
			(at 0 0 0)
			(layer "B.SilkS")
			(hide yes)
			(effects
				(font
					(size 1.27 1.27)
				)
				(justify mirror)
			)
		)
		(property "Value" ""
			(at 0 0 0)
			(layer "B.Fab")
			(effects
				(font
					(size 1.27 1.27)
				)
				(justify mirror)
			)
		)
		(duplicate_pad_numbers_are_jumpers no)
		(fp_line
			(start -0.7874 -0.4064)
			(end -0.7874 0.4064)
			(stroke
				(width 0.1524)
				(type default)
			)
			(layer "B.SilkS")
		)
		(fp_line
			(start -0.7874 0.4064)
			(end 0.7874 0.4064)
			(stroke
				(width 0.1524)
				(type default)
			)
			(layer "B.SilkS")
		)
		(fp_line
			(start 0.7874 -0.4064)
			(end -0.7874 -0.4064)
			(stroke
				(width 0.1524)
				(type default)
			)
			(layer "B.SilkS")
		)
		(fp_line
			(start 0.7874 0.4064)
			(end 0.7874 -0.4064)
			(stroke
				(width 0.1524)
				(type default)
			)
			(layer "B.SilkS")
		)
		(fp_line
			(start -0.67945 -0.3048)
			(end -0.67945 0.3048)
			(stroke
				(width 0.1)
				(type default)
			)
			(layer "B.Fab")
		)
		(fp_line
			(start -0.67945 0.3048)
			(end -0.120396 0.3048)
			(stroke
				(width 0.1)
				(type default)
			)
			(layer "B.Fab")
		)
		(fp_line
			(start -0.12065 -0.3048)
			(end -0.67945 -0.3048)
			(stroke
				(width 0.1)
				(type default)
			)
			(layer "B.Fab")
		)
		(fp_line
			(start -0.12065 -0.2794)
			(end -0.12065 -0.3048)
			(stroke
				(width 0.1)
				(type default)
			)
			(layer "B.Fab")
		)
		(fp_line
			(start -0.120396 0.2794)
			(end 0.12065 0.2794)
			(stroke
				(width 0.1)
				(type default)
			)
			(layer "B.Fab")
		)
		(fp_line
			(start -0.120396 0.3048)
			(end -0.120396 0.2794)
			(stroke
				(width 0.1)
				(type default)
			)
			(layer "B.Fab")
		)
		(fp_line
			(start 0.12065 -0.305054)
			(end 0.12065 -0.2794)
			(stroke
				(width 0.1)
				(type default)
			)
			(layer "B.Fab")
		)
		(fp_line
			(start 0.12065 -0.2794)
			(end -0.12065 -0.2794)
			(stroke
				(width 0.1)
				(type default)
			)
			(layer "B.Fab")
		)
		(fp_line
			(start 0.12065 0.2794)
			(end 0.12065 0.3048)
			(stroke
				(width 0.1)
				(type default)
			)
			(layer "B.Fab")
		)
		(fp_line
			(start 0.12065 0.3048)
			(end 0.67945 0.3048)
			(stroke
				(width 0.1)
				(type default)
			)
			(layer "B.Fab")
		)
		(fp_line
			(start 0.67945 -0.305054)
			(end 0.12065 -0.305054)
			(stroke
				(width 0.1)
				(type default)
			)
			(layer "B.Fab")
		)
		(fp_line
			(start 0.67945 0.3048)
			(end 0.67945 -0.305054)
			(stroke
				(width 0.1)
				(type default)
			)
			(layer "B.Fab")
		)
		(pad "1" smd circle
			(at 0.40005 0 180)
			(size 0 0)
			(layers "B.Cu" "B.Mask" "B.Paste")
			(net "NIC0_SLOT_ID1")
		)
		(pad "2" smd circle
			(at -0.40005 0 180)
			(size 0 0)
			(layers "B.Cu" "B.Mask" "B.Paste")
			(net "P3V3_NIC0")
		)
	)
	(footprint ""
		(layer "B.Cu")
		(at 379.857 -244.729 180)
		(property "Reference" "R932"
			(at 0 0 0)
			(layer "B.SilkS")
			(hide yes)
			(effects
				(font
					(size 1.27 1.27)
				)
				(justify mirror)
			)
		)
		(property "Value" ""
			(at 0 0 0)
			(layer "B.Fab")
			(effects
				(font
					(size 1.27 1.27)
				)
				(justify mirror)
			)
		)
		(duplicate_pad_numbers_are_jumpers no)
		(fp_line
			(start 0.7874 0.4064)
			(end 0.7874 -0.4064)
			(stroke
				(width 0.1524)
				(type default)
			)
			(layer "B.SilkS")
		)
		(fp_line
			(start 0.7874 -0.4064)
			(end -0.7874 -0.4064)
			(stroke
				(width 0.1524)
				(type default)
			)
			(layer "B.SilkS")
		)
		(fp_line
			(start -0.7874 0.4064)
			(end 0.7874 0.4064)
			(stroke
				(width 0.1524)
				(type default)
			)
			(layer "B.SilkS")
		)
		(fp_line
			(start -0.7874 -0.4064)
			(end -0.7874 0.4064)
			(stroke
				(width 0.1524)
				(type default)
			)
			(layer "B.SilkS")
		)
		(fp_line
			(start 0.67945 0.3048)
			(end 0.67945 -0.305054)
			(stroke
				(width 0.1)
				(type default)
			)
			(layer "B.Fab")
		)
		(fp_line
			(start 0.67945 -0.305054)
			(end 0.12065 -0.305054)
			(stroke
				(width 0.1)
				(type default)
			)
			(layer "B.Fab")
		)
		(fp_line
			(start 0.12065 0.3048)
			(end 0.67945 0.3048)
			(stroke
				(width 0.1)
				(type default)
			)
			(layer "B.Fab")
		)
		(fp_line
			(start 0.12065 0.2794)
			(end 0.12065 0.3048)
			(stroke
				(width 0.1)
				(type default)
			)
			(layer "B.Fab")
		)
		(fp_line
			(start 0.12065 -0.2794)
			(end -0.12065 -0.2794)
			(stroke
				(width 0.1)
				(type default)
			)
			(layer "B.Fab")
		)
		(fp_line
			(start 0.12065 -0.305054)
			(end 0.12065 -0.2794)
			(stroke
				(width 0.1)
				(type default)
			)
			(layer "B.Fab")
		)
		(fp_line
			(start -0.120396 0.3048)
			(end -0.120396 0.2794)
			(stroke
				(width 0.1)
				(type default)
			)
			(layer "B.Fab")
		)
		(fp_line
			(start -0.120396 0.2794)
			(end 0.12065 0.2794)
			(stroke
				(width 0.1)
				(type default)
			)
			(layer "B.Fab")
		)
		(fp_line
			(start -0.12065 -0.2794)
			(end -0.12065 -0.3048)
			(stroke
				(width 0.1)
				(type default)
			)
			(layer "B.Fab")
		)
		(fp_line
			(start -0.12065 -0.3048)
			(end -0.67945 -0.3048)
			(stroke
				(width 0.1)
				(type default)
			)
			(layer "B.Fab")
		)
		(fp_line
			(start -0.67945 0.3048)
			(end -0.120396 0.3048)
			(stroke
				(width 0.1)
				(type default)
			)
			(layer "B.Fab")
		)
		(fp_line
			(start -0.67945 -0.3048)
			(end -0.67945 0.3048)
			(stroke
				(width 0.1)
				(type default)
			)
			(layer "B.Fab")
		)
		(pad "1" smd circle
			(at 0.40005 0)
			(size 0 0)
			(layers "B.Cu" "B.Mask" "B.Paste")
			(net "UART_PEX1_SDB_BUF_TX")
		)
		(pad "2" smd circle
			(at -0.40005 0)
			(size 0 0)
			(layers "B.Cu" "B.Mask" "B.Paste")
			(net "P3V3_AUX")
		)
	)
	(footprint ""
		(layer "B.Cu")
		(at 73.400158 -110.978696)
		(property "Reference" "C866"
			(at 0 0 0)
			(layer "B.SilkS")
			(hide yes)
			(effects
				(font
					(size 1.27 1.27)
				)
				(justify mirror)
			)
		)
		(property "Value" ""
			(at 0 0 0)
			(layer "B.Fab")
			(effects
				(font
					(size 1.27 1.27)
				)
				(justify mirror)
			)
		)
		(duplicate_pad_numbers_are_jumpers no)
		(fp_line
			(start -0.299974 -0.150114)
			(end -0.299974 0.150114)
			(stroke
				(width 0.1)
				(type default)
			)
			(layer "B.Fab")
		)
		(fp_line
			(start -0.299974 0.150114)
			(end 0.299974 0.150114)
			(stroke
				(width 0.1)
				(type default)
			)
			(layer "B.Fab")
		)
		(fp_line
			(start 0.299974 -0.150114)
			(end -0.299974 -0.150114)
			(stroke
				(width 0.1)
				(type default)
			)
			(layer "B.Fab")
		)
		(fp_line
			(start 0.299974 0.150114)
			(end 0.299974 -0.150114)
			(stroke
				(width 0.1)
				(type default)
			)
			(layer "B.Fab")
		)
		(pad "1" smd rect
			(at 0.2667 0 180)
			(size 0.3048 0.381)
			(layers "B.Cu" "B.Mask" "B.Paste")
			(net "P12V_NIC1")
		)
		(pad "2" smd rect
			(at -0.2667 0 180)
			(size 0.3048 0.381)
			(layers "B.Cu" "B.Mask" "B.Paste")
			(net "GND")
		)
	)
)
